#ISCELL
  mstr_misc dns *
  *
#ISCELL
  pure_quanta quanta_title_block_c *
  *
#ISCELL
  logical_power universal_power *
  page181_i103
#CELL
  pure_quanta q_cap *
  page181_i104
#ISCELL
  logical_power universal_gnd *
  page181_i106
#ISCELL
  logical_power universal_power *
  page181_i108
#ISCELL
  logical_power universal_power *
  page181_i11
#CELL
  pure_quanta q_cap *
  page181_i110
#CELL
  pure_quanta q_cap *
  page181_i111
#ISCELL
  logical_power universal_gnd *
  page181_i113
#ISCELL
  logical_power universal_gnd *
  page181_i114
#ISCELL
  logical_power universal_power *
  page181_i115
#ISCELL
  logical_power universal_gnd *
  page181_i117
#ISCELL
  logical_power universal_power *
  page181_i118
#CELL
  pure_quanta q_cap *
  page181_i119
#CELL
  pure_quanta q_cap *
  page181_i12
#ISCELL
  logical_power universal_gnd *
  page181_i122
#CELL
  pure_quanta q_cap *
  page181_i123
#ISCELL
  logical_power universal_power *
  page181_i124
#CELL
  pure_quanta q_cap *
  page181_i125
#ISCELL
  logical_power universal_gnd *
  page181_i126
#CELL
  pure_quanta q_cap *
  page181_i127
#ISCELL
  logical_power universal_power *
  page181_i128
#CELL
  pure_quanta q_res *
  page181_i129
#CELL
  pure_quanta q_cap *
  page181_i13
#ISCELL
  logical_power universal_power *
  page181_i130
#CELL
  pure_quanta q_cap *
  page181_i131
#ISCELL
  logical_power universal_gnd *
  page181_i132
#CELL
  pure_quanta q_cap *
  page181_i133
#ISCELL
  logical_power universal_gnd *
  page181_i134
#CELL
  pure_quanta q_cap *
  page181_i136
#CELL
  pure_quanta q_cap *
  page181_i137
#ISCELL
  logical_power universal_power *
  page181_i138
#ISCELL
  logical_power universal_power *
  page181_i139
#ISCELL
  logical_power universal_gnd *
  page181_i14
#CELL
  pure_quanta q_cap *
  page181_i140
#ISCELL
  logical_power universal_gnd *
  page181_i141
#CELL
  pure_quanta q_cap *
  page181_i142
#ISCELL
  logical_power universal_gnd *
  page181_i143
#CELL
  pure_quanta q_res *
  page181_i144
#CELL
  pure_quanta q_inductor *
  page181_i145
#CELL
  pure_quanta q_cap *
  page181_i146
#CELL
  pure_quanta q_cap *
  page181_i147
#ISCELL
  logical_power universal_power *
  page181_i148
#ISCELL
  logical_power universal_power *
  page181_i149
#ISCELL
  logical_power universal_power *
  page181_i150
#CELL
  pure_quanta q_cap *
  page181_i151
#CELL
  pure_quanta q_cap *
  page181_i152
#CELL
  pure_quanta q_cap *
  page181_i153
#CELL
  pure_quanta q_cap *
  page181_i154
#CELL
  pure_quanta q_cap *
  page181_i155
#CELL
  pure_quanta q_cap *
  page181_i156
#CELL
  pure_quanta q_cap *
  page181_i157
#CELL
  pure_quanta q_cap *
  page181_i158
#CELL
  pure_quanta q_cap *
  page181_i159
#CELL
  pure_quanta q_cap *
  page181_i162
#CELL
  pure_quanta q_cap *
  page181_i163
#CELL
  pure_quanta q_inductor *
  page181_i164
#CELL
  pure_quanta q_res *
  page181_i165
#ISCELL
  logical_power universal_gnd *
  page181_i18
#ISCELL
  logical_power universal_power *
  page181_i20
#CELL
  pure_quanta q_cap *
  page181_i25
#ISCELL
  logical_power universal_power *
  page181_i26
#CELL
  pure_quanta q_cap *
  page181_i27
#ISCELL
  logical_power universal_gnd *
  page181_i28
#CELL
  pure_quanta q_cap *
  page181_i29
#CELL
  pure_quanta q_cap *
  page181_i30
#ISCELL
  logical_power universal_power *
  page181_i31
#CELL
  pure_quanta q_cap *
  page181_i32
#ISCELL
  logical_power universal_gnd *
  page181_i33
#ISCELL
  logical_power universal_power *
  page181_i4
#CELL
  pure_quanta q_cap *
  page181_i40
#ISCELL
  logical_power universal_power *
  page181_i41
#CELL
  pure_quanta q_cap *
  page181_i42
#CELL
  pure_quanta q_cap *
  page181_i43
#ISCELL
  logical_power universal_gnd *
  page181_i44
#CELL
  pure_quanta q_cap *
  page181_i45
#CELL
  pure_quanta q_cap *
  page181_i48
#CELL
  pure_quanta q_cap *
  page181_i49
#ISCELL
  logical_power universal_gnd *
  page181_i5
#ISCELL
  logical_power universal_gnd *
  page181_i50
#CELL
  pure_quanta q_cap *
  page181_i51
#CELL
  pure_quanta q_cap *
  page181_i58
#CELL
  pure_quanta q_cap *
  page181_i59
#CELL
  pure_quanta q_cap *
  page181_i6
#CELL
  pure_quanta q_cap *
  page181_i60
#CELL
  pure_quanta q_cap *
  page181_i61
#CELL
  pure_quanta q_cap *
  page181_i63
#ISCELL
  logical_power universal_gnd *
  page181_i64
#ISCELL
  logical_power universal_gnd *
  page181_i68
#CELL
  pure_quanta q_cap *
  page181_i7
#CELL
  pure_quanta q_cap *
  page181_i78
#CELL
  pure_quanta q_cap *
  page181_i8
#CELL
  pure_quanta q_cap *
  page181_i87
#ISCELL
  logical_power universal_gnd *
  page181_i88
#CELL
  pure_quanta q_cap *
  page181_i89
#ISCELL
  logical_power universal_power *
  page181_i90
#CELL
  pure_quanta q_cap *
  page181_i91
#ISCELL
  logical_power universal_gnd *
  page181_i92
#ISCELL
  logical_power universal_gnd *
  page181_i93
#ISCELL
  logical_power universal_power *
  page181_i94
#ISCELL
  logical_power universal_power *
  page181_i95
#ISCELL
  logical_power universal_power *
  page181_i99
